(kicad_pcb
	(version 20221018)
	(generator pcbnew)
	(general
    (thickness 1.518)
  )
	(paper "A4")
	(title_block
    (title "Kria K26 Devboard")
    (date "2024-03-26")
    (rev "1.2.5")
    (comment 1 "www.antmicro.com")
    (comment 2 "Antmicro Ltd.")
		(comment 9 "footprints 380-384 of 660")
	)
	(layers
    (0 "F.Cu" mixed)
    (1 "In1.Cu" power)
    (2 "In2.Cu" mixed)
    (3 "In3.Cu" power)
    (4 "In4.Cu" mixed)
    (5 "In5.Cu" power)
    (6 "In6.Cu" mixed)
    (31 "B.Cu" power)
    (32 "B.Adhes" user "B.Adhesive")
    (33 "F.Adhes" user "F.Adhesive")
    (34 "B.Paste" user)
    (35 "F.Paste" user)
    (36 "B.SilkS" user "B.Silkscreen")
    (37 "F.SilkS" user "F.Silkscreen")
    (38 "B.Mask" user)
    (39 "F.Mask" user)
    (40 "Dwgs.User" user "User.Drawings")
    (41 "Cmts.User" user "User.Comments")
    (42 "Eco1.User" user "User.Eco1")
    (43 "Eco2.User" user "User.Eco2")
    (44 "Edge.Cuts" user)
    (45 "Margin" user)
    (46 "B.CrtYd" user "B.Courtyard")
    (47 "F.CrtYd" user "F.Courtyard")
    (48 "B.Fab" user)
    (49 "F.Fab" user)
  )
	(footprint "kria-k26-devboard-footprints:USON-10_2.5x1mm_P0.5mm" (layer "F.Cu")
    (at 81.96 136)
    (descr "USON-10 2.5x1mm_ Pitch 0.5mm")
    (tags "USON-10 2.5x1mm Pitch 0.5mm")
    (property "Author" "Antmicro")
    (property "License" "Apache-2.0")
    (property "MPN" "TPD4E05U06QDQARQ1")
    (property "Manufacturer" "Texas Instruments")
    (property "Sheetfile" "debug.kicad_sch")
    (property "Sheetname" "Debug and JTAG")
    (property "ki_description" "ESD protection")
    (property "ki_keywords" "SMT, DIODE, IC, TVS, ESD")
    (attr smd)
    (fp_text reference "U41" (at -0.8 -1.65) (layer "F.SilkS")
        (effects (font (size 0.7 0.7) (thickness 0.15)) (justify left bottom))
    )
    (fp_text value "TPD4E05U06QDQARQ1" (at 0.018 2.499) (layer "F.Fab") hide
        (effects (font (size 0.7 0.7) (thickness 0.15)) (justify left bottom))
    )
    (fp_text user "${REFERENCE}" (at -0.802 4.498) (layer "F.Fab") hide
        (effects (font (size 0.7 0.7) (thickness 0.15)) (justify left bottom))
    )
    (fp_text user "Author: Antmicro" (at -0.802 5.7) (layer "F.Fab") hide
        (effects (font (size 0.7 0.7) (thickness 0.15)) (justify left bottom))
    )
    (fp_text user "License: Apache-2.0" (at -0.802 6.9) (layer "F.Fab") hide
        (effects (font (size 0.7 0.7) (thickness 0.15)) (justify left bottom))
    )
    (fp_line (start 0.498 -1.401) (end -0.5 -1.401)
      (stroke (width 0.15) (type solid)) (layer "F.SilkS"))
    (fp_line (start 0.498 1.398) (end -0.5 1.398)
      (stroke (width 0.15) (type solid)) (layer "F.SilkS"))
    (fp_circle (center -0.68 -1.27) (end -0.63 -1.27)
      (stroke (width 0.15) (type solid)) (fill solid) (layer "F.SilkS"))
    (fp_rect (start -0.8 -1.5) (end 0.8 1.499)
      (stroke (width 0.05) (type solid)) (fill none) (layer "F.CrtYd"))
    (fp_line (start -0.5 -1) (end -0.5 1.249)
      (stroke (width 0.15) (type solid)) (layer "F.Fab"))
    (fp_line (start -0.5 1.249) (end 0.498 1.249)
      (stroke (width 0.15) (type solid)) (layer "F.Fab"))
    (fp_line (start -0.25 -1.25) (end -0.5 -1)
      (stroke (width 0.15) (type solid)) (layer "F.Fab"))
    (fp_line (start 0.498 -1.25) (end -0.25 -1.25)
      (stroke (width 0.15) (type solid)) (layer "F.Fab"))
    (fp_line (start 0.498 -1.25) (end 0.498 1.249)
      (stroke (width 0.15) (type solid)) (layer "F.Fab"))
    (pad "1" smd roundrect (at -0.387 -1 270) (size 0.25 0.55) (layers "F.Cu" "F.Paste" "F.Mask") (roundrect_rratio 0.25)
      (net 145 "/Debug and JTAG/JTAG_TMS_C2M") (pintype "passive"))
    (pad "2" smd roundrect (at -0.387 -0.5 270) (size 0.25 0.55) (layers "F.Cu" "F.Paste" "F.Mask") (roundrect_rratio 0.25)
      (net 143 "/Debug and JTAG/JTAG_TCK_C2M") (pintype "passive"))
    (pad "3" smd roundrect (at -0.387 0 270) (size 0.4 0.55) (layers "F.Cu" "F.Paste" "F.Mask") (roundrect_rratio 0.25)
      (net 1 "GND") (pintype "power_in"))
    (pad "4" smd roundrect (at -0.387 0.498 270) (size 0.25 0.55) (layers "F.Cu" "F.Paste" "F.Mask") (roundrect_rratio 0.25)
      (net 142 "/Debug and JTAG/JTAG_TDO_M2C") (pintype "passive"))
    (pad "5" smd roundrect (at -0.387 0.998 270) (size 0.25 0.55) (layers "F.Cu" "F.Paste" "F.Mask") (roundrect_rratio 0.25)
      (net 141 "/Debug and JTAG/JTAG_TDI_C2M") (pintype "passive"))
    (pad "6" smd roundrect (at 0.385 0.998 270) (size 0.25 0.55) (layers "F.Cu" "F.Paste" "F.Mask") (roundrect_rratio 0.25)
      (net 141 "/Debug and JTAG/JTAG_TDI_C2M") (pintype "passive"))
    (pad "7" smd roundrect (at 0.385 0.498 270) (size 0.25 0.55) (layers "F.Cu" "F.Paste" "F.Mask") (roundrect_rratio 0.25)
      (net 142 "/Debug and JTAG/JTAG_TDO_M2C") (pintype "passive"))
    (pad "8" smd roundrect (at 0.385 0 270) (size 0.4 0.55) (layers "F.Cu" "F.Paste" "F.Mask") (roundrect_rratio 0.25)
      (net 1 "GND") (pintype "passive"))
    (pad "9" smd roundrect (at 0.385 -0.5 270) (size 0.25 0.55) (layers "F.Cu" "F.Paste" "F.Mask") (roundrect_rratio 0.25)
      (net 143 "/Debug and JTAG/JTAG_TCK_C2M") (pintype "passive"))
    (pad "10" smd roundrect (at 0.385 -1 270) (size 0.25 0.55) (layers "F.Cu" "F.Paste" "F.Mask") (roundrect_rratio 0.25)
      (net 145 "/Debug and JTAG/JTAG_TMS_C2M") (pintype "passive"))
  )
	(footprint "kria-k26-devboard-footprints:WSON-6-1EP_2x2mm_P0.65mm" (layer "F.Cu")
    (at 151.9 111 90)
    (property "Author" "Antmicro")
    (property "License" "Apache-2.0")
    (property "MPN" "NCP730BMT330TBG")
    (property "Manufacturer" "ON Semiconductor")
    (property "Sheetfile" "debug.kicad_sch")
    (property "Sheetname" "Debug and JTAG")
    (property "ki_description" "Linear Voltage Regulator IC Positive Fixed 1 Output 150mA 6-WDFN (2x2)")
    (property "ki_keywords" "SMT, PMIC, IC, LDO, VOLTAGE, REGULATOR")
    (attr smd)
    (fp_text reference "U38" (at -0.43 -1.13 90) (layer "F.SilkS")
        (effects (font (size 0.7 0.7) (thickness 0.15)) (justify left bottom))
    )
    (fp_text value "NCP730BMT330_WSON" (at 0 2.2 90) (layer "F.Fab") hide
        (effects (font (size 0.7 0.7) (thickness 0.15)) (justify left bottom))
    )
    (fp_text user "Author: Antmicro" (at -1.01 5.2 90) (layer "F.Fab") hide
        (effects (font (size 0.7 0.7) (thickness 0.15)) (justify left bottom))
    )
    (fp_text user "License: Apache-2.0" (at -1.01 6.4 90) (layer "F.Fab") hide
        (effects (font (size 0.7 0.7) (thickness 0.15)) (justify left bottom))
    )
    (fp_text user "${REFERENCE}" (at -1.01 3.999 90) (layer "F.Fab") hide
        (effects (font (size 0.7 0.7) (thickness 0.15)) (justify left bottom))
    )
    (fp_line (start -1 1) (end 1 1)
      (stroke (width 0.12) (type solid)) (layer "F.SilkS"))
    (fp_line (start 1 -1) (end -1.05 -1)
      (stroke (width 0.12) (type solid)) (layer "F.SilkS"))
    (fp_circle (center -1.275 -1.075) (end -1.224 -1.075)
      (stroke (width 0.15) (type solid)) (fill solid) (layer "F.SilkS"))
    (fp_rect (start -1.45 -1.25) (end 1.45 1.25)
      (stroke (width 0.05) (type solid)) (fill none) (layer "F.CrtYd"))
    (pad "1" smd roundrect (at -0.975 -0.652 90) (size 0.45 0.4) (layers "F.Cu" "F.Paste" "F.Mask") (roundrect_rratio 0.25)
      (net 138 "/Debug and JTAG/USB_3V3") (pinfunction "V_{OUT}") (pintype "power_out"))
    (pad "2" smd roundrect (at -0.975 0 90) (size 0.45 0.4) (layers "F.Cu" "F.Paste" "F.Mask") (roundrect_rratio 0.25)
      (net 734 "unconnected-(U38-NC-Pad2)") (pinfunction "NC") (pintype "no_connect"))
    (pad "3" smd roundrect (at -0.975 0.65 90) (size 0.45 0.4) (layers "F.Cu" "F.Paste" "F.Mask") (roundrect_rratio 0.25)
      (net 1 "GND") (pinfunction "GND") (pintype "power_in"))
    (pad "4" smd roundrect (at 0.973 0.65 90) (size 0.45 0.4) (layers "F.Cu" "F.Paste" "F.Mask") (roundrect_rratio 0.25)
      (net 313 "/Debug and JTAG/USB_VBUS") (pinfunction "EN") (pintype "input"))
    (pad "5" smd roundrect (at 0.973 0 90) (size 0.45 0.4) (layers "F.Cu" "F.Paste" "F.Mask") (roundrect_rratio 0.25)
      (net 735 "unconnected-(U38-PG-Pad5)") (pinfunction "PG") (pintype "open_collector+no_connect"))
    (pad "6" smd roundrect (at 0.973 -0.652 90) (size 0.45 0.4) (layers "F.Cu" "F.Paste" "F.Mask") (roundrect_rratio 0.25)
      (net 313 "/Debug and JTAG/USB_VBUS") (pinfunction "V_{IN}") (pintype "power_in"))
    (pad "7" smd roundrect (at 0 0 90) (size 1.12 1.72) (layers "F.Cu" "F.Paste" "F.Mask") (roundrect_rratio 0.1)
      (net 1 "GND") (pinfunction "GND") (pintype "passive"))
  )
	(footprint "kria-k26-devboard-footprints:USON-10_2.5x1mm_P0.5mm" (layer "F.Cu")
    (at 174.3 141.9 -90)
    (descr "USON-10 2.5x1mm_ Pitch 0.5mm")
    (tags "USON-10 2.5x1mm Pitch 0.5mm")
    (property "Author" "Antmicro")
    (property "License" "Apache-2.0")
    (property "MPN" "TPD4E05U06QDQARQ1")
    (property "Manufacturer" "Texas Instruments")
    (property "Sheetfile" "pmod.kicad_sch")
    (property "Sheetname" "PMOD")
    (property "ki_description" "ESD protection")
    (property "ki_keywords" "SMT, DIODE, IC, TVS, ESD")
    (attr smd)
    (fp_text reference "U15" (at 0.018 -1.7 -90) (layer "F.SilkS")
        (effects (font (size 0.7 0.7) (thickness 0.15)) (justify left bottom))
    )
    (fp_text value "TPD4E05U06QDQARQ1" (at 0.018 2.499 -90) (layer "F.Fab")
        (effects (font (size 0.7 0.7) (thickness 0.15)) (justify left bottom))
    )
    (fp_text user "Author: Antmicro" (at -0.802 5.7 -90) (layer "F.Fab") hide
        (effects (font (size 0.7 0.7) (thickness 0.15)) (justify left bottom))
    )
    (fp_text user "License: Apache-2.0" (at -0.802 6.9 -90) (layer "F.Fab") hide
        (effects (font (size 0.7 0.7) (thickness 0.15)) (justify left bottom))
    )
    (fp_text user "${REFERENCE}" (at -0.802 4.498 -90) (layer "F.Fab") hide
        (effects (font (size 0.7 0.7) (thickness 0.15)) (justify left bottom))
    )
    (fp_line (start 0.498 -1.401) (end -0.5 -1.401)
      (stroke (width 0.15) (type solid)) (layer "F.SilkS"))
    (fp_line (start 0.498 1.398) (end -0.5 1.398)
      (stroke (width 0.15) (type solid)) (layer "F.SilkS"))
    (fp_circle (center -0.68 -1.27) (end -0.63 -1.27)
      (stroke (width 0.15) (type solid)) (fill solid) (layer "F.SilkS"))
    (fp_rect (start -0.8 -1.5) (end 0.8 1.499)
      (stroke (width 0.05) (type solid)) (fill none) (layer "F.CrtYd"))
    (fp_line (start -0.5 -1) (end -0.5 1.249)
      (stroke (width 0.15) (type solid)) (layer "F.Fab"))
    (fp_line (start -0.5 1.249) (end 0.498 1.249)
      (stroke (width 0.15) (type solid)) (layer "F.Fab"))
    (fp_line (start -0.25 -1.25) (end -0.5 -1)
      (stroke (width 0.15) (type solid)) (layer "F.Fab"))
    (fp_line (start 0.498 -1.25) (end -0.25 -1.25)
      (stroke (width 0.15) (type solid)) (layer "F.Fab"))
    (fp_line (start 0.498 -1.25) (end 0.498 1.249)
      (stroke (width 0.15) (type solid)) (layer "F.Fab"))
    (pad "1" smd roundrect (at -0.387 -1 180) (size 0.25 0.55) (layers "F.Cu" "F.Paste" "F.Mask") (roundrect_rratio 0.25)
      (net 146 "/PMOD/HDA15") (pintype "passive"))
    (pad "2" smd roundrect (at -0.387 -0.5 180) (size 0.25 0.55) (layers "F.Cu" "F.Paste" "F.Mask") (roundrect_rratio 0.25)
      (net 147 "/PMOD/HDA16_CC") (pintype "passive"))
    (pad "3" smd roundrect (at -0.387 0 180) (size 0.4 0.55) (layers "F.Cu" "F.Paste" "F.Mask") (roundrect_rratio 0.25)
      (net 1 "GND") (pintype "power_in"))
    (pad "4" smd roundrect (at -0.387 0.498 180) (size 0.25 0.55) (layers "F.Cu" "F.Paste" "F.Mask") (roundrect_rratio 0.25)
      (net 148 "/PMOD/HDA17") (pintype "passive"))
    (pad "5" smd roundrect (at -0.387 0.998 180) (size 0.25 0.55) (layers "F.Cu" "F.Paste" "F.Mask") (roundrect_rratio 0.25)
      (net 152 "/PMOD/HDA18") (pintype "passive"))
    (pad "6" smd roundrect (at 0.385 0.998 180) (size 0.25 0.55) (layers "F.Cu" "F.Paste" "F.Mask") (roundrect_rratio 0.25)
      (net 152 "/PMOD/HDA18") (pintype "passive"))
    (pad "7" smd roundrect (at 0.385 0.498 180) (size 0.25 0.55) (layers "F.Cu" "F.Paste" "F.Mask") (roundrect_rratio 0.25)
      (net 148 "/PMOD/HDA17") (pintype "passive"))
    (pad "8" smd roundrect (at 0.385 0 180) (size 0.4 0.55) (layers "F.Cu" "F.Paste" "F.Mask") (roundrect_rratio 0.25)
      (net 1 "GND") (pintype "passive"))
    (pad "9" smd roundrect (at 0.385 -0.5 180) (size 0.25 0.55) (layers "F.Cu" "F.Paste" "F.Mask") (roundrect_rratio 0.25)
      (net 147 "/PMOD/HDA16_CC") (pintype "passive"))
    (pad "10" smd roundrect (at 0.385 -1 180) (size 0.25 0.55) (layers "F.Cu" "F.Paste" "F.Mask") (roundrect_rratio 0.25)
      (net 146 "/PMOD/HDA15") (pintype "passive"))
  )
	(footprint "kria-k26-devboard-footprints:D_SOD-323F" (layer "F.Cu")
    (at 154.31 111.01 -90)
    (property "Author" "Antmicro")
    (property "License" "Apache-2.0")
    (property "MPN" "1N4148WS")
    (property "Manufacturer" "ON Semiconductor")
    (property "Sheetfile" "debug.kicad_sch")
    (property "Sheetname" "Debug and JTAG")
    (property "ki_description" "Small Signal Fast Switching Diode")
    (attr smd)
    (fp_text reference "D7" (at 2.95 -0.935 -90) (layer "F.SilkS")
        (effects (font (size 0.7 0.7) (thickness 0.15)) (justify left bottom))
    )
    (fp_text value "1N4148WS" (at -1.7 1.9 -90) (layer "F.Fab") hide
        (effects (font (size 0.7 0.7) (thickness 0.15)) (justify left bottom))
    )
    (fp_text user "Author: Antmicro" (at -1.8 4.46 -90) (layer "F.Fab") hide
        (effects (font (size 0.7 0.7) (thickness 0.15)) (justify left bottom))
    )
    (fp_text user "${REFERENCE}" (at -1.8 3.2 -90) (layer "F.Fab") hide
        (effects (font (size 0.7 0.7) (thickness 0.15)) (justify left bottom))
    )
    (fp_text user "License: Apache-2.0" (at -1.8 5.8 -90) (layer "F.Fab") hide
        (effects (font (size 0.7 0.7) (thickness 0.15)) (justify left bottom))
    )
    (fp_line (start -0.975 -0.75) (end -0.975 -0.45)
      (stroke (width 0.15) (type solid)) (layer "F.SilkS"))
    (fp_line (start -0.975 0.748) (end -0.975 0.45)
      (stroke (width 0.15) (type solid)) (layer "F.SilkS"))
    (fp_line (start -0.625 -0.75) (end -0.975 -0.75)
      (stroke (width 0.15) (type solid)) (layer "F.SilkS"))
    (fp_line (start -0.625 0.748) (end -0.975 0.748)
      (stroke (width 0.15) (type solid)) (layer "F.SilkS"))
    (fp_line (start -0.5 -0.426) (end -0.5 0.424)
      (stroke (width 0.15) (type solid)) (layer "F.SilkS"))
    (fp_line (start 0.623 -0.75) (end 0.973 -0.75)
      (stroke (width 0.15) (type solid)) (layer "F.SilkS"))
    (fp_line (start 0.973 -0.75) (end 0.973 -0.45)
      (stroke (width 0.15) (type solid)) (layer "F.SilkS"))
    (fp_line (start 0.973 0.45) (end 0.973 0.748)
      (stroke (width 0.15) (type solid)) (layer "F.SilkS"))
    (fp_line (start 0.973 0.748) (end 0.623 0.748)
      (stroke (width 0.15) (type solid)) (layer "F.SilkS"))
    (fp_rect (start -1.6 -0.827) (end 1.599 0.825)
      (stroke (width 0.05) (type solid)) (fill none) (layer "F.CrtYd"))
    (fp_line (start -0.85 -0.625) (end 0.848 -0.625)
      (stroke (width 0.15) (type solid)) (layer "F.Fab"))
    (fp_line (start -0.85 0.623) (end -0.85 -0.625)
      (stroke (width 0.15) (type solid)) (layer "F.Fab"))
    (fp_line (start -0.85 0.623) (end 0.848 0.623)
      (stroke (width 0.15) (type solid)) (layer "F.Fab"))
    (fp_line (start 0.848 -0.625) (end 0.848 0.623)
      (stroke (width 0.15) (type solid)) (layer "F.Fab"))
    (pad "A" smd roundrect (at 1.05 0 270) (size 0.8 0.6) (layers "F.Cu" "F.Paste" "F.Mask") (roundrect_rratio 0.15)
      (net 266 "/Debug and JTAG/USBB_VBUS") (pinfunction "A") (pintype "passive"))
    (pad "K" smd roundrect (at -1.051 0 270) (size 0.8 0.6) (layers "F.Cu" "F.Paste" "F.Mask") (roundrect_rratio 0.15)
      (net 313 "/Debug and JTAG/USB_VBUS") (pinfunction "K") (pintype "passive"))
  )
	(footprint "kria-k26-devboard-footprints:D_SOD-323F" (layer "F.Cu")
    (at 154.325 107.8 90)
    (property "Author" "Antmicro")
    (property "License" "Apache-2.0")
    (property "MPN" "1N4148WS")
    (property "Manufacturer" "ON Semiconductor")
    (property "Sheetfile" "debug.kicad_sch")
    (property "Sheetname" "Debug and JTAG")
    (property "ki_description" "Small Signal Fast Switching Diode")
    (attr smd)
    (fp_text reference "D6" (at 1.53 0.295 90) (layer "F.SilkS")
        (effects (font (size 0.7 0.7) (thickness 0.15)) (justify left bottom))
    )
    (fp_text value "1N4148WS" (at -1.7 1.9 90) (layer "F.Fab") hide
        (effects (font (size 0.7 0.7) (thickness 0.15)) (justify left bottom))
    )
    (fp_text user "License: Apache-2.0" (at -1.8 5.8 90) (layer "F.Fab") hide
        (effects (font (size 0.7 0.7) (thickness 0.15)) (justify left bottom))
    )
    (fp_text user "${REFERENCE}" (at -1.8 3.2 90) (layer "F.Fab") hide
        (effects (font (size 0.7 0.7) (thickness 0.15)) (justify left bottom))
    )
    (fp_text user "Author: Antmicro" (at -1.8 4.46 90) (layer "F.Fab") hide
        (effects (font (size 0.7 0.7) (thickness 0.15)) (justify left bottom))
    )
    (fp_line (start -0.975 -0.75) (end -0.975 -0.45)
      (stroke (width 0.15) (type solid)) (layer "F.SilkS"))
    (fp_line (start -0.975 0.748) (end -0.975 0.45)
      (stroke (width 0.15) (type solid)) (layer "F.SilkS"))
    (fp_line (start -0.625 -0.75) (end -0.975 -0.75)
      (stroke (width 0.15) (type solid)) (layer "F.SilkS"))
    (fp_line (start -0.625 0.748) (end -0.975 0.748)
      (stroke (width 0.15) (type solid)) (layer "F.SilkS"))
    (fp_line (start -0.5 -0.426) (end -0.5 0.424)
      (stroke (width 0.15) (type solid)) (layer "F.SilkS"))
    (fp_line (start 0.623 -0.75) (end 0.973 -0.75)
      (stroke (width 0.15) (type solid)) (layer "F.SilkS"))
    (fp_line (start 0.973 -0.75) (end 0.973 -0.45)
      (stroke (width 0.15) (type solid)) (layer "F.SilkS"))
    (fp_line (start 0.973 0.45) (end 0.973 0.748)
      (stroke (width 0.15) (type solid)) (layer "F.SilkS"))
    (fp_line (start 0.973 0.748) (end 0.623 0.748)
      (stroke (width 0.15) (type solid)) (layer "F.SilkS"))
    (fp_rect (start -1.6 -0.827) (end 1.599 0.825)
      (stroke (width 0.05) (type solid)) (fill none) (layer "F.CrtYd"))
    (fp_line (start -0.85 -0.625) (end 0.848 -0.625)
      (stroke (width 0.15) (type solid)) (layer "F.Fab"))
    (fp_line (start -0.85 0.623) (end -0.85 -0.625)
      (stroke (width 0.15) (type solid)) (layer "F.Fab"))
    (fp_line (start -0.85 0.623) (end 0.848 0.623)
      (stroke (width 0.15) (type solid)) (layer "F.Fab"))
    (fp_line (start 0.848 -0.625) (end 0.848 0.623)
      (stroke (width 0.15) (type solid)) (layer "F.Fab"))
    (pad "A" smd roundrect (at 1.05 0 90) (size 0.8 0.6) (layers "F.Cu" "F.Paste" "F.Mask") (roundrect_rratio 0.15)
      (net 265 "/Debug and JTAG/USBC_VBUS") (pinfunction "A") (pintype "passive"))
    (pad "K" smd roundrect (at -1.051 0 90) (size 0.8 0.6) (layers "F.Cu" "F.Paste" "F.Mask") (roundrect_rratio 0.15)
      (net 313 "/Debug and JTAG/USB_VBUS") (pinfunction "K") (pintype "passive"))
  )
)
